(kicad_pcb
	(version 20260206)
	(generator "pcbnew")
	(generator_version "10.0")
	(general
		(thickness 1.6)
		(legacy_teardrops no)
	)
	(paper "A4")
	(title_block
		(title "Bryce Canyon_R.DPB_16317-1_OCP.brd")
		(comment 1 "Bryce Canyon / footprints 655-661 of 2099")
	)
	(layers
		(0 "F.Cu" signal "TOP")
		(4 "In1.Cu" signal "L2GND")
		(6 "In2.Cu" signal "L3")
		(8 "In3.Cu" signal "L4VCC")
		(10 "In4.Cu" signal "L5VCC")
		(12 "In5.Cu" signal "L6")
		(14 "In6.Cu" signal "L7GND")
		(2 "B.Cu" signal "BOTTOM")
		(9 "F.Adhes" user "F.Adhesive")
		(11 "B.Adhes" user "B.Adhesive")
		(13 "F.Paste" user "Package Geometry/Pastemask Top")
		(15 "B.Paste" user "Package Geometry/Pastemask Bottom")
		(5 "F.SilkS" user "Ref Des/Silkscreen Top")
		(7 "B.SilkS" user "Ref Des/Silkscreen Bottom")
		(1 "F.Mask" user "Board Geometry/Soldermask Top")
		(3 "B.Mask" user "Board Geometry/Soldermask Bottom")
		(17 "Dwgs.User" user "User.Drawings")
		(19 "Cmts.User" user "User.Comments")
		(21 "Eco1.User" user "User.Eco1")
		(23 "Eco2.User" user "User.Eco2")
		(25 "Edge.Cuts" user "Board Geometry/Outline")
		(27 "Margin" user)
		(31 "F.CrtYd" user "Package Geometry/Place Bound Top")
		(29 "B.CrtYd" user "Package Geometry/Place Bound Bottom")
		(35 "F.Fab" user "Ref Des/Assembly Top")
		(33 "B.Fab" user "Ref Des/Assembly Bottom")
	)
	(footprint ""
		(layer "F.Cu")
		(at 368.3 -33.02)
		(property "Reference" "Q162"
			(at 0 0 0)
			(layer "F.SilkS")
			(hide yes)
			(effects
				(font
					(size 1.27 1.27)
				)
			)
		)
		(property "Value" "AO4407AL-GP"
			(at -3.707384 -1.5367 0)
			(unlocked yes)
			(layer "F.Fab")
			(hide yes)
			(effects
				(font
					(size 1.016 1.016)
					(thickness 0.1524)
				)
			)
		)
		(property "Device Type" "SOIC8H69"
			(at -3.707384 -3.0607 0)
			(unlocked yes)
			(layer "F.Fab")
			(hide yes)
			(effects
				(font
					(size 1.016 1.016)
					(thickness 0.1524)
				)
			)
		)
		(duplicate_pad_numbers_are_jumpers no)
		(fp_line
			(start -2.7432 -1.4224)
			(end -2.7432 1.4224)
			(stroke
				(width 0.1524)
				(type default)
			)
			(layer "F.SilkS")
		)
		(fp_line
			(start -2.7432 1.4224)
			(end -2.6416 1.4224)
			(stroke
				(width 0.1524)
				(type default)
			)
			(layer "F.SilkS")
		)
		(fp_line
			(start -2.7432 1.4224)
			(end 2.1336 1.4224)
			(stroke
				(width 0.1524)
				(type default)
			)
			(layer "F.SilkS")
		)
		(fp_line
			(start -2.7178 -0.508)
			(end -2.1844 -0.0508)
			(stroke
				(width 0.1524)
				(type default)
			)
			(layer "F.SilkS")
		)
		(fp_line
			(start -2.6289 3.4417)
			(end -2.6289 1.4732)
			(stroke
				(width 0.381)
				(type default)
			)
			(layer "F.SilkS")
		)
		(fp_line
			(start -2.1844 -0.0508)
			(end -2.7178 0.508)
			(stroke
				(width 0.1524)
				(type default)
			)
			(layer "F.SilkS")
		)
		(fp_line
			(start 2.1336 -1.4224)
			(end -2.7432 -1.4224)
			(stroke
				(width 0.1524)
				(type default)
			)
			(layer "F.SilkS")
		)
		(fp_line
			(start 2.1336 1.4224)
			(end 2.1336 -1.4224)
			(stroke
				(width 0.1524)
				(type default)
			)
			(layer "F.SilkS")
		)
		(fp_poly
			(pts
				(xy -2.2098 -1.4224) (xy -2.2098 1.4224) (xy 2.2098 1.4224) (xy 2.2098 -1.4224)
			)
			(stroke
				(width 0)
				(type default)
			)
			(fill yes)
			(layer "F.SilkS")
		)
		(fp_rect
			(start -2.450084 2.999994)
			(end 2.450084 -2.999994)
			(stroke
				(width 0)
				(type default)
			)
			(fill no)
			(layer "F.CrtYd")
		)
		(fp_poly
			(pts
				(xy -2.8194 3.6322) (xy -2.8194 -3.6322) (xy 2.8194 -3.6322) (xy 2.8194 1.18364) (xy 2.450084 1.18364)
				(xy 2.450084 -2.999994) (xy -2.450084 -2.999994) (xy -2.450084 2.999994) (xy 2.450084 2.999994)
				(xy 2.450084 1.18618) (xy 2.8194 1.18618) (xy 2.8194 3.6322)
			)
			(stroke
				(width 0)
				(type default)
			)
			(fill no)
			(layer "F.CrtYd")
		)
		(fp_rect
			(start -2.8194 3.6322)
			(end 2.8194 -3.6322)
			(stroke
				(width 0)
				(type default)
			)
			(fill no)
			(layer "F.Fab")
		)
		(pad "1" smd rect
			(at -1.905 2.54)
			(size 0.635 1.651)
			(layers "F.Cu" "F.Mask" "F.Paste")
			(net "P12V_B")
		)
		(pad "2" smd rect
			(at -0.635 2.54)
			(size 0.635 1.651)
			(layers "F.Cu" "F.Mask" "F.Paste")
			(net "P12V_B")
		)
		(pad "3" smd rect
			(at 0.635 2.54)
			(size 0.635 1.651)
			(layers "F.Cu" "F.Mask" "F.Paste")
			(net "P12V_B")
		)
		(pad "4" smd rect
			(at 1.905 2.54)
			(size 0.635 1.651)
			(layers "F.Cu" "F.Mask" "F.Paste")
			(net "SW_HDD_N31")
		)
		(pad "5" smd rect
			(at 1.905 -2.54)
			(size 0.635 1.651)
			(layers "F.Cu" "F.Mask" "F.Paste")
			(net "P12V_HDD31")
		)
		(pad "6" smd rect
			(at 0.635 -2.54)
			(size 0.635 1.651)
			(layers "F.Cu" "F.Mask" "F.Paste")
			(net "P12V_HDD31")
		)
		(pad "7" smd rect
			(at -0.635 -2.54)
			(size 0.635 1.651)
			(layers "F.Cu" "F.Mask" "F.Paste")
			(net "P12V_HDD31")
		)
		(pad "8" smd rect
			(at -1.905 -2.54)
			(size 0.635 1.651)
			(layers "F.Cu" "F.Mask" "F.Paste")
			(net "P12V_HDD31")
		)
	)
	(footprint ""
		(layer "F.Cu")
		(at 268.224 -209.3595 90)
		(property "Reference" "R13"
			(at 0 0 90)
			(layer "F.SilkS")
			(hide yes)
			(effects
				(font
					(size 1.27 1.27)
				)
			)
		)
		(property "Value" "1KR2J-1-GP"
			(at 0.064008 -3.993896 90)
			(unlocked yes)
			(layer "F.Fab")
			(hide yes)
			(effects
				(font
					(size 1.016 1.016)
					(thickness 0.1524)
				)
			)
		)
		(property "Device Type" "R402H16"
			(at 0.064008 -5.517896 90)
			(unlocked yes)
			(layer "F.Fab")
			(hide yes)
			(effects
				(font
					(size 1.016 1.016)
					(thickness 0.1524)
				)
			)
		)
		(duplicate_pad_numbers_are_jumpers no)
		(fp_line
			(start 0.508 -0.9398)
			(end -0.508 -0.9398)
			(stroke
				(width 0.1524)
				(type default)
			)
			(layer "F.SilkS")
		)
		(fp_line
			(start -0.508 -0.9398)
			(end -0.508 0.9398)
			(stroke
				(width 0.1524)
				(type default)
			)
			(layer "F.SilkS")
		)
		(fp_rect
			(start -0.508 0.9398)
			(end 0.508 -0.9398)
			(stroke
				(width 0)
				(type default)
			)
			(fill no)
			(layer "F.CrtYd")
		)
		(fp_rect
			(start -0.508 0.9398)
			(end 0.508 -0.9398)
			(stroke
				(width 0)
				(type default)
			)
			(fill no)
			(layer "F.Fab")
		)
		(pad "1" smd custom
			(at 0 -0.4445 90)
			(size 0.1397 0.1397)
			(layers "F.Cu" "F.Mask" "F.Paste")
			(net "P3V3_STBY_B")
			(options
				(clearance outline)
				(anchor circle)
			)
			(primitives
				(gr_poly
					(pts
						(arc
							(start -0.1778 -0.2794)
							(mid -0.249642 -0.249642)
							(end -0.2794 -0.1778)
						)
						(arc
							(start -0.2794 0.1778)
							(mid -0.249642 0.249642)
							(end -0.1778 0.2794)
						)
						(arc
							(start 0.1778 0.2794)
							(mid 0.249642 0.249642)
							(end 0.2794 0.1778)
						)
						(arc
							(start 0.2794 -0.1778)
							(mid 0.249642 -0.249642)
							(end 0.1778 -0.2794)
						)
					)
					(width 0)
					(fill yes)
				)
			)
		)
		(pad "2" smd custom
			(at 0 0.4445 90)
			(size 0.1397 0.1397)
			(layers "F.Cu" "F.Mask" "F.Paste")
			(net "I2C_DRIVE_B_FLT_LED_SDA")
			(options
				(clearance outline)
				(anchor circle)
			)
			(primitives
				(gr_poly
					(pts
						(arc
							(start -0.1778 -0.2794)
							(mid -0.249642 -0.249642)
							(end -0.2794 -0.1778)
						)
						(arc
							(start -0.2794 0.1778)
							(mid -0.249642 0.249642)
							(end -0.1778 0.2794)
						)
						(arc
							(start 0.1778 0.2794)
							(mid 0.249642 0.249642)
							(end 0.2794 0.1778)
						)
						(arc
							(start 0.2794 -0.1778)
							(mid 0.249642 -0.249642)
							(end 0.1778 -0.2794)
						)
					)
					(width 0)
					(fill yes)
				)
			)
		)
	)
	(footprint ""
		(layer "F.Cu")
		(at 369.57 -250.444 90)
		(property "Reference" "R282"
			(at 0 0 90)
			(layer "F.SilkS")
			(hide yes)
			(effects
				(font
					(size 1.27 1.27)
				)
			)
		)
		(property "Value" "200KR2F-L-GP"
			(at 0.064008 -3.993896 90)
			(unlocked yes)
			(layer "F.Fab")
			(hide yes)
			(effects
				(font
					(size 1.016 1.016)
					(thickness 0.1524)
				)
			)
		)
		(property "Device Type" "R402H16"
			(at 0.064008 -5.517896 90)
			(unlocked yes)
			(layer "F.Fab")
			(hide yes)
			(effects
				(font
					(size 1.016 1.016)
					(thickness 0.1524)
				)
			)
		)
		(duplicate_pad_numbers_are_jumpers no)
		(fp_line
			(start 0.508 -0.9398)
			(end -0.508 -0.9398)
			(stroke
				(width 0.1524)
				(type default)
			)
			(layer "F.SilkS")
		)
		(fp_line
			(start -0.508 -0.9398)
			(end -0.508 0.9398)
			(stroke
				(width 0.1524)
				(type default)
			)
			(layer "F.SilkS")
		)
		(fp_rect
			(start -0.508 0.9398)
			(end 0.508 -0.9398)
			(stroke
				(width 0)
				(type default)
			)
			(fill no)
			(layer "F.CrtYd")
		)
		(fp_rect
			(start -0.508 0.9398)
			(end 0.508 -0.9398)
			(stroke
				(width 0)
				(type default)
			)
			(fill no)
			(layer "F.Fab")
		)
		(pad "1" smd custom
			(at 0 -0.4445 90)
			(size 0.1397 0.1397)
			(layers "F.Cu" "F.Mask" "F.Paste")
			(net "SW_HDD_R7")
			(options
				(clearance outline)
				(anchor circle)
			)
			(primitives
				(gr_poly
					(pts
						(arc
							(start -0.1778 -0.2794)
							(mid -0.249642 -0.249642)
							(end -0.2794 -0.1778)
						)
						(arc
							(start -0.2794 0.1778)
							(mid -0.249642 0.249642)
							(end -0.1778 0.2794)
						)
						(arc
							(start 0.1778 0.2794)
							(mid 0.249642 0.249642)
							(end 0.2794 0.1778)
						)
						(arc
							(start 0.2794 -0.1778)
							(mid 0.249642 -0.249642)
							(end 0.1778 -0.2794)
						)
					)
					(width 0)
					(fill yes)
				)
			)
		)
		(pad "2" smd custom
			(at 0 0.4445 90)
			(size 0.1397 0.1397)
			(layers "F.Cu" "F.Mask" "F.Paste")
			(net "SW_HDD_N7")
			(options
				(clearance outline)
				(anchor circle)
			)
			(primitives
				(gr_poly
					(pts
						(arc
							(start -0.1778 -0.2794)
							(mid -0.249642 -0.249642)
							(end -0.2794 -0.1778)
						)
						(arc
							(start -0.2794 0.1778)
							(mid -0.249642 0.249642)
							(end -0.1778 0.2794)
						)
						(arc
							(start 0.1778 0.2794)
							(mid 0.249642 0.249642)
							(end 0.2794 0.1778)
						)
						(arc
							(start 0.2794 -0.1778)
							(mid 0.249642 -0.249642)
							(end 0.1778 -0.2794)
						)
					)
					(width 0)
					(fill yes)
				)
			)
		)
	)
	(footprint ""
		(layer "F.Cu")
		(at 44.54906 -118.310406 180)
		(property "Reference" "R1134"
			(at 0 0 180)
			(layer "F.SilkS")
			(hide yes)
			(effects
				(font
					(size 1.27 1.27)
				)
			)
		)
		(property "Value" "619KR2F-GP"
			(at 0.064008 -3.993896 180)
			(unlocked yes)
			(layer "F.Fab")
			(hide yes)
			(effects
				(font
					(size 1.016 1.016)
					(thickness 0.1524)
				)
			)
		)
		(property "Device Type" "R402H16"
			(at 0.064008 -5.517896 180)
			(unlocked yes)
			(layer "F.Fab")
			(hide yes)
			(effects
				(font
					(size 1.016 1.016)
					(thickness 0.1524)
				)
			)
		)
		(duplicate_pad_numbers_are_jumpers no)
		(fp_line
			(start 0.508 -0.9398)
			(end -0.508 -0.9398)
			(stroke
				(width 0.1524)
				(type default)
			)
			(layer "F.SilkS")
		)
		(fp_line
			(start -0.508 -0.9398)
			(end -0.508 0.9398)
			(stroke
				(width 0.1524)
				(type default)
			)
			(layer "F.SilkS")
		)
		(fp_rect
			(start -0.508 0.9398)
			(end 0.508 -0.9398)
			(stroke
				(width 0)
				(type default)
			)
			(fill no)
			(layer "F.CrtYd")
		)
		(fp_rect
			(start -0.508 0.9398)
			(end 0.508 -0.9398)
			(stroke
				(width 0)
				(type default)
			)
			(fill no)
			(layer "F.Fab")
		)
		(pad "1" smd custom
			(at 0 -0.4445 180)
			(size 0.1397 0.1397)
			(layers "F.Cu" "F.Mask" "F.Paste")
			(net "P5V_B_2_RF")
			(options
				(clearance outline)
				(anchor circle)
			)
			(primitives
				(gr_poly
					(pts
						(arc
							(start -0.1778 -0.2794)
							(mid -0.249642 -0.249642)
							(end -0.2794 -0.1778)
						)
						(arc
							(start -0.2794 0.1778)
							(mid -0.249642 0.249642)
							(end -0.1778 0.2794)
						)
						(arc
							(start 0.1778 0.2794)
							(mid 0.249642 0.249642)
							(end 0.2794 0.1778)
						)
						(arc
							(start 0.2794 -0.1778)
							(mid 0.249642 -0.249642)
							(end 0.1778 -0.2794)
						)
					)
					(width 0)
					(fill yes)
				)
			)
		)
		(pad "2" smd custom
			(at 0 0.4445 180)
			(size 0.1397 0.1397)
			(layers "F.Cu" "F.Mask" "F.Paste")
			(net "AGND_P5V_B_2")
			(options
				(clearance outline)
				(anchor circle)
			)
			(primitives
				(gr_poly
					(pts
						(arc
							(start -0.1778 -0.2794)
							(mid -0.249642 -0.249642)
							(end -0.2794 -0.1778)
						)
						(arc
							(start -0.2794 0.1778)
							(mid -0.249642 0.249642)
							(end -0.1778 0.2794)
						)
						(arc
							(start 0.1778 0.2794)
							(mid 0.249642 0.249642)
							(end 0.2794 0.1778)
						)
						(arc
							(start 0.2794 -0.1778)
							(mid 0.249642 -0.249642)
							(end 0.1778 -0.2794)
						)
					)
					(width 0)
					(fill yes)
				)
			)
		)
	)
	(footprint ""
		(layer "F.Cu")
		(at 457.93533 -229.963218 90)
		(property "Reference" "R1146"
			(at 0 0 90)
			(layer "F.SilkS")
			(hide yes)
			(effects
				(font
					(size 1.27 1.27)
				)
			)
		)
		(property "Value" "100KR2F-L1-GP"
			(at 0.064008 -3.993896 90)
			(unlocked yes)
			(layer "F.Fab")
			(hide yes)
			(effects
				(font
					(size 1.016 1.016)
					(thickness 0.1524)
				)
			)
		)
		(property "Device Type" "R402H16"
			(at 0.064008 -5.517896 90)
			(unlocked yes)
			(layer "F.Fab")
			(hide yes)
			(effects
				(font
					(size 1.016 1.016)
					(thickness 0.1524)
				)
			)
		)
		(duplicate_pad_numbers_are_jumpers no)
		(fp_line
			(start 0.508 -0.9398)
			(end -0.508 -0.9398)
			(stroke
				(width 0.1524)
				(type default)
			)
			(layer "F.SilkS")
		)
		(fp_line
			(start -0.508 -0.9398)
			(end -0.508 0.9398)
			(stroke
				(width 0.1524)
				(type default)
			)
			(layer "F.SilkS")
		)
		(fp_rect
			(start -0.508 0.9398)
			(end 0.508 -0.9398)
			(stroke
				(width 0)
				(type default)
			)
			(fill no)
			(layer "F.CrtYd")
		)
		(fp_rect
			(start -0.508 0.9398)
			(end 0.508 -0.9398)
			(stroke
				(width 0)
				(type default)
			)
			(fill no)
			(layer "F.Fab")
		)
		(pad "1" smd custom
			(at 0 -0.4445 90)
			(size 0.1397 0.1397)
			(layers "F.Cu" "F.Mask" "F.Paste")
			(net "AGND_P5V_B_3")
			(options
				(clearance outline)
				(anchor circle)
			)
			(primitives
				(gr_poly
					(pts
						(arc
							(start -0.1778 -0.2794)
							(mid -0.249642 -0.249642)
							(end -0.2794 -0.1778)
						)
						(arc
							(start -0.2794 0.1778)
							(mid -0.249642 0.249642)
							(end -0.1778 0.2794)
						)
						(arc
							(start 0.1778 0.2794)
							(mid 0.249642 0.249642)
							(end 0.2794 0.1778)
						)
						(arc
							(start 0.2794 -0.1778)
							(mid 0.249642 -0.249642)
							(end 0.1778 -0.2794)
						)
					)
					(width 0)
					(fill yes)
				)
			)
		)
		(pad "2" smd custom
			(at 0 0.4445 90)
			(size 0.1397 0.1397)
			(layers "F.Cu" "F.Mask" "F.Paste")
			(net "P5V_B_3_MODE")
			(options
				(clearance outline)
				(anchor circle)
			)
			(primitives
				(gr_poly
					(pts
						(arc
							(start -0.1778 -0.2794)
							(mid -0.249642 -0.249642)
							(end -0.2794 -0.1778)
						)
						(arc
							(start -0.2794 0.1778)
							(mid -0.249642 0.249642)
							(end -0.1778 0.2794)
						)
						(arc
							(start 0.1778 0.2794)
							(mid 0.249642 0.249642)
							(end 0.2794 0.1778)
						)
						(arc
							(start 0.2794 -0.1778)
							(mid 0.249642 -0.249642)
							(end 0.1778 -0.2794)
						)
					)
					(width 0)
					(fill yes)
				)
			)
		)
	)
	(footprint ""
		(layer "F.Cu")
		(at 54.37886 -120.342406)
		(property "Reference" "TP203"
			(at 0 0 0)
			(layer "F.SilkS")
			(hide yes)
			(effects
				(font
					(size 1.27 1.27)
				)
			)
		)
		(property "Value" "*"
			(at -0.0508 -1.6764 0)
			(unlocked yes)
			(layer "F.Fab")
			(hide yes)
			(effects
				(font
					(size 1.016 1.016)
					(thickness 0.1524)
				)
			)
		)
		(property "Device Type" "TPAD32"
			(at -0.0508 -3.2004 0)
			(unlocked yes)
			(layer "F.Fab")
			(hide yes)
			(effects
				(font
					(size 1.016 1.016)
					(thickness 0.1524)
				)
			)
		)
		(duplicate_pad_numbers_are_jumpers no)
		(fp_poly
			(pts
				(arc
					(start 0.4064 0)
					(mid -0.4064 0)
					(end 0.4064 0)
				)
			)
			(stroke
				(width 0)
				(type default)
			)
			(fill no)
			(layer "F.CrtYd")
		)
		(fp_poly
			(pts
				(arc
					(start 0.7112 0)
					(mid -0.7112 0)
					(end 0.7112 0)
				)
			)
			(stroke
				(width 0)
				(type default)
			)
			(fill no)
			(layer "F.Fab")
		)
		(pad "1" smd circle
			(at 0 0)
			(size 0.8128 0.8128)
			(layers "F.Cu" "F.Mask" "F.Paste")
			(net "P5V_B_2_PGOOD")
		)
	)
	(footprint ""
		(layer "F.Cu")
		(at 134.1628 -370.7384 180)
		(property "Reference" "R940"
			(at 0 0 180)
			(layer "F.SilkS")
			(hide yes)
			(effects
				(font
					(size 1.27 1.27)
				)
			)
		)
		(property "Value" "27KR3F-GP"
			(at -0.0254 -2.5146 180)
			(unlocked yes)
			(layer "F.Fab")
			(hide yes)
			(effects
				(font
					(size 1.016 1.016)
					(thickness 0.1524)
				)
			)
		)
		(property "Device Type" "R603H22"
			(at -0.0254 -4.0386 180)
			(unlocked yes)
			(layer "F.Fab")
			(hide yes)
			(effects
				(font
					(size 1.016 1.016)
					(thickness 0.1524)
				)
			)
		)
		(duplicate_pad_numbers_are_jumpers no)
		(fp_line
			(start 0.2032 0)
			(end 0.4826 0)
			(stroke
				(width 0.2032)
				(type default)
			)
			(layer "F.SilkS")
		)
		(fp_line
			(start -0.4826 0)
			(end -0.2032 0)
			(stroke
				(width 0.2032)
				(type default)
			)
			(layer "F.SilkS")
		)
		(fp_rect
			(start -0.5842 1.3335)
			(end 0.5842 -1.3335)
			(stroke
				(width 0)
				(type default)
			)
			(fill no)
			(layer "F.CrtYd")
		)
		(fp_rect
			(start -0.5842 1.3335)
			(end 0.5842 -1.3335)
			(stroke
				(width 0)
				(type default)
			)
			(fill no)
			(layer "F.Fab")
		)
		(pad "1" smd custom
			(at 0 -0.762 180)
			(size 0.2159 0.2159)
			(layers "F.Cu" "F.Mask" "F.Paste")
			(net "FAN_1_TACH1")
			(options
				(clearance outline)
				(anchor circle)
			)
			(primitives
				(gr_poly
					(pts
						(arc
							(start -0.3302 -0.4318)
							(mid -0.402042 -0.402042)
							(end -0.4318 -0.3302)
						)
						(arc
							(start -0.4318 0.3302)
							(mid -0.402042 0.402042)
							(end -0.3302 0.4318)
						)
						(arc
							(start 0.3302 0.4318)
							(mid 0.402042 0.402042)
							(end 0.4318 0.3302)
						)
						(arc
							(start 0.4318 -0.3302)
							(mid 0.402042 -0.402042)
							(end 0.3302 -0.4318)
						)
					)
					(width 0)
					(fill yes)
				)
			)
		)
		(pad "2" smd custom
			(at 0 0.762 180)
			(size 0.2159 0.2159)
			(layers "F.Cu" "F.Mask" "F.Paste")
			(net "FANTACH_F1")
			(options
				(clearance outline)
				(anchor circle)
			)
			(primitives
				(gr_poly
					(pts
						(arc
							(start -0.3302 -0.4318)
							(mid -0.402042 -0.402042)
							(end -0.4318 -0.3302)
						)
						(arc
							(start -0.4318 0.3302)
							(mid -0.402042 0.402042)
							(end -0.3302 0.4318)
						)
						(arc
							(start 0.3302 0.4318)
							(mid 0.402042 0.402042)
							(end 0.4318 0.3302)
						)
						(arc
							(start 0.4318 -0.3302)
							(mid 0.402042 -0.402042)
							(end 0.3302 -0.4318)
						)
					)
					(width 0)
					(fill yes)
				)
			)
		)
	)
)
